# T6G (Grand Teton) — schematic netlist excerpt (pin names and nets, part order shuffled) for the footprints in the layout excerpt that follows; sources: Cadence DE-HDL packaged netlist, KiCad conversion of 04192023_DAF0TMB3IC0_F0TG_MB_C_brd_V02_OCP.brd

C2165  Q_CAP  22UF 4V 20% X6S  pkg C0402  page 69 : A = PVDDCR_CPU0_P0 ; B = GND
C2169  Q_CAP  22UF 4V 20% X6S  pkg C0402  page 69 : A = PVDDCR_CPU0_P0 ; B = GND

(kicad_pcb
	(version 20260206)
	(generator "pcbnew")
	(generator_version "10.0")
	(general
		(thickness 1.6)
		(legacy_teardrops no)
	)
	(paper "A4")
	(title_block
		(title "04192023_DAF0TMB3IC0_F0TG_MB_C_brd_V02_OCP.brd")
		(comment 1 "Grand Teton / footprints 8260-8261 of 8354")
	)
	(layers
		(0 "F.Cu" signal "TOP")
		(4 "In1.Cu" signal "GND")
		(6 "In2.Cu" signal "IN1")
		(8 "In3.Cu" signal "GND1")
		(10 "In4.Cu" signal "IN2")
		(12 "In5.Cu" signal "GND2")
		(14 "In6.Cu" signal "IN3")
		(16 "In7.Cu" signal "GND3")
		(18 "In8.Cu" signal "VCC")
		(20 "In9.Cu" signal "VCC1")
		(22 "In10.Cu" signal "GND4")
		(24 "In11.Cu" signal "IN4")
		(26 "In12.Cu" signal "GND5")
		(28 "In13.Cu" signal "IN5")
		(30 "In14.Cu" signal "GND6")
		(32 "In15.Cu" signal "IN6")
		(34 "In16.Cu" signal "GND7")
		(2 "B.Cu" signal "BOTTOM")
		(9 "F.Adhes" user "F.Adhesive")
		(11 "B.Adhes" user "B.Adhesive")
		(13 "F.Paste" user "Package Geometry/Pastemask Top")
		(15 "B.Paste" user "Package Geometry/Pastemask Bottom")
		(5 "F.SilkS" user "Ref Des/Silkscreen Top")
		(7 "B.SilkS" user "Ref Des/Silkscreen Bottom")
		(1 "F.Mask" user "Board Geometry/Soldermask Top")
		(3 "B.Mask" user "Board Geometry/Soldermask Bottom")
		(17 "Dwgs.User" user "User.Drawings")
		(19 "Cmts.User" user "User.Comments")
		(21 "Eco1.User" user "User.Eco1")
		(23 "Eco2.User" user "User.Eco2")
		(25 "Edge.Cuts" user "Board Geometry/Outline")
		(27 "Margin" user)
		(31 "F.CrtYd" user "Package Geometry/Place Bound Top")
		(29 "B.CrtYd" user "Package Geometry/Place Bound Bottom")
		(35 "F.Fab" user "Ref Des/Assembly Top")
		(33 "B.Fab" user "Ref Des/Assembly Bottom")
	)
	(footprint ""
		(layer "B.Cu")
		(at 352.596958 -250.89231 180)
		(property "Reference" "C2165"
			(at 0 0 0)
			(layer "B.SilkS")
			(hide yes)
			(effects
				(font
					(size 1.27 1.27)
				)
				(justify mirror)
			)
		)
		(property "Value" ""
			(at 0 0 0)
			(layer "B.Fab")
			(effects
				(font
					(size 1.27 1.27)
				)
				(justify mirror)
			)
		)
		(duplicate_pad_numbers_are_jumpers no)
		(fp_line
			(start 0.7874 0.4064)
			(end 0.7874 -0.4064)
			(stroke
				(width 0.1524)
				(type default)
			)
			(layer "B.SilkS")
		)
		(fp_line
			(start 0.7874 -0.4064)
			(end -0.7874 -0.4064)
			(stroke
				(width 0.1524)
				(type default)
			)
			(layer "B.SilkS")
		)
		(fp_line
			(start -0.7874 0.4064)
			(end 0.7874 0.4064)
			(stroke
				(width 0.1524)
				(type default)
			)
			(layer "B.SilkS")
		)
		(fp_line
			(start -0.7874 -0.4064)
			(end -0.7874 0.4064)
			(stroke
				(width 0.1524)
				(type default)
			)
			(layer "B.SilkS")
		)
		(fp_line
			(start 0.67945 0.3048)
			(end 0.67945 -0.305054)
			(stroke
				(width 0.1)
				(type default)
			)
			(layer "B.Fab")
		)
		(fp_line
			(start 0.67945 -0.305054)
			(end 0.12065 -0.305054)
			(stroke
				(width 0.1)
				(type default)
			)
			(layer "B.Fab")
		)
		(fp_line
			(start 0.12065 0.3048)
			(end 0.67945 0.3048)
			(stroke
				(width 0.1)
				(type default)
			)
			(layer "B.Fab")
		)
		(fp_line
			(start 0.12065 0.2794)
			(end 0.12065 0.3048)
			(stroke
				(width 0.1)
				(type default)
			)
			(layer "B.Fab")
		)
		(fp_line
			(start 0.12065 -0.2794)
			(end -0.12065 -0.2794)
			(stroke
				(width 0.1)
				(type default)
			)
			(layer "B.Fab")
		)
		(fp_line
			(start 0.12065 -0.305054)
			(end 0.12065 -0.2794)
			(stroke
				(width 0.1)
				(type default)
			)
			(layer "B.Fab")
		)
		(fp_line
			(start -0.120396 0.3048)
			(end -0.120396 0.2794)
			(stroke
				(width 0.1)
				(type default)
			)
			(layer "B.Fab")
		)
		(fp_line
			(start -0.120396 0.2794)
			(end 0.12065 0.2794)
			(stroke
				(width 0.1)
				(type default)
			)
			(layer "B.Fab")
		)
		(fp_line
			(start -0.12065 -0.2794)
			(end -0.12065 -0.3048)
			(stroke
				(width 0.1)
				(type default)
			)
			(layer "B.Fab")
		)
		(fp_line
			(start -0.12065 -0.3048)
			(end -0.67945 -0.3048)
			(stroke
				(width 0.1)
				(type default)
			)
			(layer "B.Fab")
		)
		(fp_line
			(start -0.67945 0.3048)
			(end -0.120396 0.3048)
			(stroke
				(width 0.1)
				(type default)
			)
			(layer "B.Fab")
		)
		(fp_line
			(start -0.67945 -0.3048)
			(end -0.67945 0.3048)
			(stroke
				(width 0.1)
				(type default)
			)
			(layer "B.Fab")
		)
		(pad "1" smd circle
			(at 0.40005 0)
			(size 0 0)
			(layers "B.Cu" "B.Mask" "B.Paste")
			(net "PVDDCR_CPU0_P0")
		)
		(pad "2" smd circle
			(at -0.40005 0)
			(size 0 0)
			(layers "B.Cu" "B.Mask" "B.Paste")
			(net "GND")
		)
	)
	(footprint ""
		(layer "B.Cu")
		(at 366.217454 -248.47931 180)
		(property "Reference" "C2169"
			(at 0 0 0)
			(layer "B.SilkS")
			(hide yes)
			(effects
				(font
					(size 1.27 1.27)
				)
				(justify mirror)
			)
		)
		(property "Value" ""
			(at 0 0 0)
			(layer "B.Fab")
			(effects
				(font
					(size 1.27 1.27)
				)
				(justify mirror)
			)
		)
		(duplicate_pad_numbers_are_jumpers no)
		(fp_line
			(start 0.7874 0.4064)
			(end 0.7874 -0.4064)
			(stroke
				(width 0.1524)
				(type default)
			)
			(layer "B.SilkS")
		)
		(fp_line
			(start 0.7874 -0.4064)
			(end -0.7874 -0.4064)
			(stroke
				(width 0.1524)
				(type default)
			)
			(layer "B.SilkS")
		)
		(fp_line
			(start -0.7874 0.4064)
			(end 0.7874 0.4064)
			(stroke
				(width 0.1524)
				(type default)
			)
			(layer "B.SilkS")
		)
		(fp_line
			(start -0.7874 -0.4064)
			(end -0.7874 0.4064)
			(stroke
				(width 0.1524)
				(type default)
			)
			(layer "B.SilkS")
		)
		(fp_line
			(start 0.67945 0.3048)
			(end 0.67945 -0.305054)
			(stroke
				(width 0.1)
				(type default)
			)
			(layer "B.Fab")
		)
		(fp_line
			(start 0.67945 -0.305054)
			(end 0.12065 -0.305054)
			(stroke
				(width 0.1)
				(type default)
			)
			(layer "B.Fab")
		)
		(fp_line
			(start 0.12065 0.3048)
			(end 0.67945 0.3048)
			(stroke
				(width 0.1)
				(type default)
			)
			(layer "B.Fab")
		)
		(fp_line
			(start 0.12065 0.2794)
			(end 0.12065 0.3048)
			(stroke
				(width 0.1)
				(type default)
			)
			(layer "B.Fab")
		)
		(fp_line
			(start 0.12065 -0.2794)
			(end -0.12065 -0.2794)
			(stroke
				(width 0.1)
				(type default)
			)
			(layer "B.Fab")
		)
		(fp_line
			(start 0.12065 -0.305054)
			(end 0.12065 -0.2794)
			(stroke
				(width 0.1)
				(type default)
			)
			(layer "B.Fab")
		)
		(fp_line
			(start -0.120396 0.3048)
			(end -0.120396 0.2794)
			(stroke
				(width 0.1)
				(type default)
			)
			(layer "B.Fab")
		)
		(fp_line
			(start -0.120396 0.2794)
			(end 0.12065 0.2794)
			(stroke
				(width 0.1)
				(type default)
			)
			(layer "B.Fab")
		)
		(fp_line
			(start -0.12065 -0.2794)
			(end -0.12065 -0.3048)
			(stroke
				(width 0.1)
				(type default)
			)
			(layer "B.Fab")
		)
		(fp_line
			(start -0.12065 -0.3048)
			(end -0.67945 -0.3048)
			(stroke
				(width 0.1)
				(type default)
			)
			(layer "B.Fab")
		)
		(fp_line
			(start -0.67945 0.3048)
			(end -0.120396 0.3048)
			(stroke
				(width 0.1)
				(type default)
			)
			(layer "B.Fab")
		)
		(fp_line
			(start -0.67945 -0.3048)
			(end -0.67945 0.3048)
			(stroke
				(width 0.1)
				(type default)
			)
			(layer "B.Fab")
		)
		(pad "1" smd circle
			(at 0.40005 0)
			(size 0 0)
			(layers "B.Cu" "B.Mask" "B.Paste")
			(net "PVDDCR_CPU0_P0")
		)
		(pad "2" smd circle
			(at -0.40005 0)
			(size 0 0)
			(layers "B.Cu" "B.Mask" "B.Paste")
			(net "GND")
		)
	)
)
